# S9S_MB_2U (Grand Teton) — schematic netlist excerpt (pin names and nets, part order shuffled) for the footprints in the layout excerpt that follows; sources: Cadence DE-HDL packaged netlist, KiCad conversion of 03242023_DA0F0TMBIJ0_F0T_Motherboard_J_brd_V01_OCP.brd

PC1599  Q_CAP  22UF 10V 20% X6S  pkg C0805  page 259 : A = P3V3_AUX ; B = GND
R196  Q_RES  49.9 1% CHIP  pkg 0402LF  page 123 : A = H_CPU_NMI_LVC1_N ; B = H_CPU1_NMI_LVC1_N
C85  Q_CAP  10UF 16V 10% X6S  pkg C0805  page 109 : A = P12V_S3_AUX_CPU1_NVDIMM ; B = GND

(kicad_pcb
	(version 20260206)
	(generator "pcbnew")
	(generator_version "10.0")
	(general
		(thickness 1.6)
		(legacy_teardrops no)
	)
	(paper "A4")
	(title_block
		(title "03242023_DA0F0TMBIJ0_F0T_Motherboard_J_brd_V01_OCP.brd")
		(comment 1 "Grand Teton / footprints 4833-4835 of 6105")
	)
	(layers
		(0 "F.Cu" signal "TOP")
		(4 "In1.Cu" signal "GND")
		(6 "In2.Cu" signal "IN1")
		(8 "In3.Cu" signal "GND1")
		(10 "In4.Cu" signal "IN2")
		(12 "In5.Cu" signal "GND2")
		(14 "In6.Cu" signal "IN3")
		(16 "In7.Cu" signal "GND3")
		(18 "In8.Cu" signal "VCC")
		(20 "In9.Cu" signal "VCC1")
		(22 "In10.Cu" signal "GND4")
		(24 "In11.Cu" signal "IN4")
		(26 "In12.Cu" signal "GND5")
		(28 "In13.Cu" signal "IN5")
		(30 "In14.Cu" signal "GND6")
		(32 "In15.Cu" signal "IN6")
		(34 "In16.Cu" signal "GND7")
		(2 "B.Cu" signal "BOTTOM")
		(9 "F.Adhes" user "F.Adhesive")
		(11 "B.Adhes" user "B.Adhesive")
		(13 "F.Paste" user "Package Geometry/Pastemask Top")
		(15 "B.Paste" user "Package Geometry/Pastemask Bottom")
		(5 "F.SilkS" user "Ref Des/Silkscreen Top")
		(7 "B.SilkS" user "Ref Des/Silkscreen Bottom")
		(1 "F.Mask" user "Board Geometry/Soldermask Top")
		(3 "B.Mask" user "Board Geometry/Soldermask Bottom")
		(17 "Dwgs.User" user "User.Drawings")
		(19 "Cmts.User" user "User.Comments")
		(21 "Eco1.User" user "User.Eco1")
		(23 "Eco2.User" user "User.Eco2")
		(25 "Edge.Cuts" user "Board Geometry/Outline")
		(27 "Margin" user)
		(31 "F.CrtYd" user "Package Geometry/Place Bound Top")
		(29 "B.CrtYd" user "Package Geometry/Place Bound Bottom")
		(35 "F.Fab" user "Ref Des/Assembly Top")
		(33 "B.Fab" user "Ref Des/Assembly Bottom")
	)
	(footprint ""
		(layer "B.Cu")
		(at 81.446624 -184.096152 -90)
		(property "Reference" "R196"
			(at 0 0 90)
			(layer "B.SilkS")
			(hide yes)
			(effects
				(font
					(size 1.27 1.27)
				)
				(justify mirror)
			)
		)
		(property "Value" ""
			(at 0 0 90)
			(layer "B.Fab")
			(effects
				(font
					(size 1.27 1.27)
				)
				(justify mirror)
			)
		)
		(duplicate_pad_numbers_are_jumpers no)
		(fp_line
			(start -0.7874 0.4064)
			(end 0.7874 0.4064)
			(stroke
				(width 0.1524)
				(type default)
			)
			(layer "B.SilkS")
		)
		(fp_line
			(start 0.7874 0.4064)
			(end 0.7874 -0.4064)
			(stroke
				(width 0.1524)
				(type default)
			)
			(layer "B.SilkS")
		)
		(fp_line
			(start -0.7874 -0.4064)
			(end -0.7874 0.4064)
			(stroke
				(width 0.1524)
				(type default)
			)
			(layer "B.SilkS")
		)
		(fp_line
			(start 0.7874 -0.4064)
			(end -0.7874 -0.4064)
			(stroke
				(width 0.1524)
				(type default)
			)
			(layer "B.SilkS")
		)
		(fp_line
			(start -0.67945 0.3048)
			(end -0.120396 0.3048)
			(stroke
				(width 0.1)
				(type default)
			)
			(layer "B.Fab")
		)
		(fp_line
			(start -0.120396 0.3048)
			(end -0.120396 0.2794)
			(stroke
				(width 0.1)
				(type default)
			)
			(layer "B.Fab")
		)
		(fp_line
			(start 0.12065 0.3048)
			(end 0.67945 0.3048)
			(stroke
				(width 0.1)
				(type default)
			)
			(layer "B.Fab")
		)
		(fp_line
			(start 0.67945 0.3048)
			(end 0.67945 -0.305054)
			(stroke
				(width 0.1)
				(type default)
			)
			(layer "B.Fab")
		)
		(fp_line
			(start -0.120396 0.2794)
			(end 0.12065 0.2794)
			(stroke
				(width 0.1)
				(type default)
			)
			(layer "B.Fab")
		)
		(fp_line
			(start 0.12065 0.2794)
			(end 0.12065 0.3048)
			(stroke
				(width 0.1)
				(type default)
			)
			(layer "B.Fab")
		)
		(fp_line
			(start -0.12065 -0.2794)
			(end -0.12065 -0.3048)
			(stroke
				(width 0.1)
				(type default)
			)
			(layer "B.Fab")
		)
		(fp_line
			(start 0.12065 -0.2794)
			(end -0.12065 -0.2794)
			(stroke
				(width 0.1)
				(type default)
			)
			(layer "B.Fab")
		)
		(fp_line
			(start -0.67945 -0.3048)
			(end -0.67945 0.3048)
			(stroke
				(width 0.1)
				(type default)
			)
			(layer "B.Fab")
		)
		(fp_line
			(start -0.12065 -0.3048)
			(end -0.67945 -0.3048)
			(stroke
				(width 0.1)
				(type default)
			)
			(layer "B.Fab")
		)
		(fp_line
			(start 0.12065 -0.305054)
			(end 0.12065 -0.2794)
			(stroke
				(width 0.1)
				(type default)
			)
			(layer "B.Fab")
		)
		(fp_line
			(start 0.67945 -0.305054)
			(end 0.12065 -0.305054)
			(stroke
				(width 0.1)
				(type default)
			)
			(layer "B.Fab")
		)
		(pad "1" smd circle
			(at 0.40005 0 90)
			(size 0 0)
			(layers "B.Cu" "B.Mask" "B.Paste")
			(net "H_CPU_NMI_LVC1_N")
		)
		(pad "2" smd circle
			(at -0.40005 0 90)
			(size 0 0)
			(layers "B.Cu" "B.Mask" "B.Paste")
			(net "H_CPU1_NMI_LVC1_N")
		)
	)
	(footprint ""
		(layer "B.Cu")
		(at 449.808092 -58.325512 -90)
		(property "Reference" "PC1599"
			(at 0 0 90)
			(layer "B.SilkS")
			(hide yes)
			(effects
				(font
					(size 1.27 1.27)
				)
				(justify mirror)
			)
		)
		(property "Value" ""
			(at 0 0 90)
			(layer "B.Fab")
			(effects
				(font
					(size 1.27 1.27)
				)
				(justify mirror)
			)
		)
		(duplicate_pad_numbers_are_jumpers no)
		(fp_line
			(start -1.524 0.762)
			(end 1.524 0.762)
			(stroke
				(width 0.1524)
				(type default)
			)
			(layer "B.SilkS")
		)
		(fp_line
			(start 1.524 0.762)
			(end 1.524 -0.762)
			(stroke
				(width 0.1524)
				(type default)
			)
			(layer "B.SilkS")
		)
		(fp_line
			(start -1.524 -0.762)
			(end -1.524 0.762)
			(stroke
				(width 0.1524)
				(type default)
			)
			(layer "B.SilkS")
		)
		(fp_line
			(start 1.524 -0.762)
			(end -1.524 -0.762)
			(stroke
				(width 0.1524)
				(type default)
			)
			(layer "B.SilkS")
		)
		(fp_line
			(start -1.1049 0.724916)
			(end -1.1049 -0.724916)
			(stroke
				(width 0.1)
				(type default)
			)
			(layer "B.Fab")
		)
		(fp_line
			(start 1.1049 0.724916)
			(end -1.1049 0.724916)
			(stroke
				(width 0.1)
				(type default)
			)
			(layer "B.Fab")
		)
		(fp_line
			(start -1.1049 -0.724916)
			(end 1.1049 -0.724916)
			(stroke
				(width 0.1)
				(type default)
			)
			(layer "B.Fab")
		)
		(fp_line
			(start 1.1049 -0.724916)
			(end 1.1049 0.724916)
			(stroke
				(width 0.1)
				(type default)
			)
			(layer "B.Fab")
		)
		(pad "1" smd rect
			(at 0.889 0 270)
			(size 1.016 1.27)
			(layers "B.Cu" "B.Mask" "B.Paste")
			(net "P3V3_AUX")
		)
		(pad "2" smd rect
			(at -0.889 0 270)
			(size 1.016 1.27)
			(layers "B.Cu" "B.Mask" "B.Paste")
			(net "GND")
		)
	)
	(footprint ""
		(layer "B.Cu")
		(at 177.977546 -321.554856 -90)
		(property "Reference" "C85"
			(at 0 0 90)
			(layer "B.SilkS")
			(hide yes)
			(effects
				(font
					(size 1.27 1.27)
				)
				(justify mirror)
			)
		)
		(property "Value" ""
			(at 0 0 90)
			(layer "B.Fab")
			(effects
				(font
					(size 1.27 1.27)
				)
				(justify mirror)
			)
		)
		(duplicate_pad_numbers_are_jumpers no)
		(fp_line
			(start -1.524 0.762)
			(end 1.524 0.762)
			(stroke
				(width 0.1524)
				(type default)
			)
			(layer "B.SilkS")
		)
		(fp_line
			(start 1.524 0.762)
			(end 1.524 -0.762)
			(stroke
				(width 0.1524)
				(type default)
			)
			(layer "B.SilkS")
		)
		(fp_line
			(start -1.524 -0.762)
			(end -1.524 0.762)
			(stroke
				(width 0.1524)
				(type default)
			)
			(layer "B.SilkS")
		)
		(fp_line
			(start 1.524 -0.762)
			(end -1.524 -0.762)
			(stroke
				(width 0.1524)
				(type default)
			)
			(layer "B.SilkS")
		)
		(fp_line
			(start -1.1049 0.724916)
			(end -1.1049 -0.724916)
			(stroke
				(width 0.1)
				(type default)
			)
			(layer "B.Fab")
		)
		(fp_line
			(start 1.1049 0.724916)
			(end -1.1049 0.724916)
			(stroke
				(width 0.1)
				(type default)
			)
			(layer "B.Fab")
		)
		(fp_line
			(start -1.1049 -0.724916)
			(end 1.1049 -0.724916)
			(stroke
				(width 0.1)
				(type default)
			)
			(layer "B.Fab")
		)
		(fp_line
			(start 1.1049 -0.724916)
			(end 1.1049 0.724916)
			(stroke
				(width 0.1)
				(type default)
			)
			(layer "B.Fab")
		)
		(pad "1" smd rect
			(at 0.889 0 270)
			(size 1.016 1.27)
			(layers "B.Cu" "B.Mask" "B.Paste")
			(net "P12V_S3_AUX_CPU1_NVDIMM")
		)
		(pad "2" smd rect
			(at -0.889 0 270)
			(size 1.016 1.27)
			(layers "B.Cu" "B.Mask" "B.Paste")
			(net "GND")
		)
	)
)
